# BASEBOARD_FAB2 (Tioga Pass) — schematic netlist excerpt (pin names and nets, part order shuffled) for the footprints in the layout excerpt that follows; sources: Cadence DE-HDL packaged netlist, KiCad conversion of Wiwynn_Tioga_Pass_MB.brd

C6B1  CAP  10UF 4V 20% X6S  pkg 0603LF  page 232 : A = PVPP_DEF ; B = GND
C1E11  CAP  0.220UF 16V 10% X7R  pkg 0402  page 207 : A = VR_PVCCIN_CPU1_PH1_BOOT ; B = VR_PVCCIN_CPU1_PH1_PHASE
C8G2  CAP  0.22UF 16V 10% X7R  pkg 0402  page 105 : A = P3E_CPU0_PE2_SS_TXN<4> ; B = P3E_CPU0_PE2_SS_C_TXN<4>

(kicad_pcb
	(version 20260206)
	(generator "pcbnew")
	(generator_version "10.0")
	(general
		(thickness 1.6)
		(legacy_teardrops no)
	)
	(paper "A4")
	(title_block
		(title "Wiwynn_Tioga_Pass_MB.brd")
		(comment 1 "Tioga Pass / footprints 1905-1907 of 4770")
	)
	(layers
		(0 "F.Cu" signal "TOP")
		(4 "In1.Cu" signal "L2GND")
		(6 "In2.Cu" signal "L3")
		(8 "In3.Cu" signal "L4GND")
		(10 "In4.Cu" signal "L5")
		(12 "In5.Cu" signal "L6GND")
		(14 "In6.Cu" signal "L7VCC")
		(16 "In7.Cu" signal "L8VCC")
		(18 "In8.Cu" signal "L9GND")
		(20 "In9.Cu" signal "L10")
		(22 "In10.Cu" signal "L11GND")
		(24 "In11.Cu" signal "L12")
		(26 "In12.Cu" signal "L13GND")
		(2 "B.Cu" signal "BOTTOM")
		(9 "F.Adhes" user "F.Adhesive")
		(11 "B.Adhes" user "B.Adhesive")
		(13 "F.Paste" user "Package Geometry/Pastemask Top")
		(15 "B.Paste" user "Package Geometry/Pastemask Bottom")
		(5 "F.SilkS" user "Ref Des/Silkscreen Top")
		(7 "B.SilkS" user "Ref Des/Silkscreen Bottom")
		(1 "F.Mask" user "Board Geometry/Soldermask Top")
		(3 "B.Mask" user "Board Geometry/Soldermask Bottom")
		(17 "Dwgs.User" user "User.Drawings")
		(19 "Cmts.User" user "User.Comments")
		(21 "Eco1.User" user "User.Eco1")
		(23 "Eco2.User" user "User.Eco2")
		(25 "Edge.Cuts" user "Board Geometry/Outline")
		(27 "Margin" user)
		(31 "F.CrtYd" user "Package Geometry/Place Bound Top")
		(29 "B.CrtYd" user "Package Geometry/Place Bound Bottom")
		(35 "F.Fab" user "Ref Des/Assembly Top")
		(33 "B.Fab" user "Ref Des/Assembly Bottom")
	)
	(footprint ""
		(layer "F.Cu")
		(at 28.8036 -58.7883 90)
		(property "Reference" "C1E11"
			(at 0 0 90)
			(layer "F.SilkS")
			(hide yes)
			(effects
				(font
					(size 1.27 1.27)
				)
			)
		)
		(property "Value" ""
			(at 0 0 90)
			(layer "F.Fab")
			(effects
				(font
					(size 1.27 1.27)
				)
			)
		)
		(duplicate_pad_numbers_are_jumpers no)
		(fp_rect
			(start -0.3048 0.9906)
			(end 0.3048 -0.1016)
			(stroke
				(width 0)
				(type default)
			)
			(fill no)
			(layer "F.CrtYd")
		)
		(fp_line
			(start 0.3048 -0.1016)
			(end -0.3048 -0.1016)
			(stroke
				(width 0.1)
				(type default)
			)
			(layer "F.Fab")
		)
		(fp_line
			(start -0.3048 -0.1016)
			(end -0.3048 0.9906)
			(stroke
				(width 0.1)
				(type default)
			)
			(layer "F.Fab")
		)
		(fp_line
			(start 0.3048 0.9906)
			(end 0.3048 -0.1016)
			(stroke
				(width 0.1)
				(type default)
			)
			(layer "F.Fab")
		)
		(fp_line
			(start -0.3048 0.9906)
			(end 0.3048 0.9906)
			(stroke
				(width 0.1)
				(type default)
			)
			(layer "F.Fab")
		)
		(pad "1" smd rect
			(at 0 0 90)
			(size 0.508 0.508)
			(layers "F.Cu" "F.Mask" "F.Paste")
			(net "VR_PVCCIN_CPU1_PH1_BOOT")
		)
		(pad "2" smd rect
			(at 0 0.889 90)
			(size 0.508 0.508)
			(layers "F.Cu" "F.Mask" "F.Paste")
			(net "VR_PVCCIN_CPU1_PH1_PHASE")
		)
		(zone
			(layer "F.Cu")
			(hatch none 0.5)
			(connect_pads
				(clearance 0)
			)
			(min_thickness 0.25)
			(keepout
				(tracks not_allowed)
				(vias allowed)
				(pads allowed)
				(copperpour not_allowed)
				(footprints allowed)
			)
			(placement
				(enabled no)
				(sheetname "")
			)
			(fill
				(thermal_gap 0.5)
				(thermal_bridge_width 0.5)
				(island_removal_mode 0)
			)
			(polygon
				(pts
					(xy 29.4386 -58.5343) (xy 29.4386 -59.0423) (xy 29.0576 -59.0423) (xy 29.0576 -58.5343)
				)
			)
		)
		(zone
			(layer "F.Cu")
			(hatch none 0.5)
			(connect_pads
				(clearance 0)
			)
			(min_thickness 0.25)
			(keepout
				(tracks allowed)
				(vias not_allowed)
				(pads allowed)
				(copperpour not_allowed)
				(footprints allowed)
			)
			(placement
				(enabled no)
				(sheetname "")
			)
			(fill
				(thermal_gap 0.5)
				(thermal_bridge_width 0.5)
				(island_removal_mode 0)
			)
			(polygon
				(pts
					(xy 29.4386 -58.5343) (xy 29.4386 -59.0423) (xy 29.0576 -59.0423) (xy 29.0576 -58.5343)
				)
			)
		)
	)
	(footprint ""
		(layer "F.Cu")
		(at 318.643 -130.3528 -90)
		(property "Reference" "C6B1"
			(at 0 0 270)
			(layer "F.SilkS")
			(hide yes)
			(effects
				(font
					(size 1.27 1.27)
				)
			)
		)
		(property "Value" ""
			(at 0 0 270)
			(layer "F.Fab")
			(effects
				(font
					(size 1.27 1.27)
				)
			)
		)
		(duplicate_pad_numbers_are_jumpers no)
		(fp_poly
			(pts
				(xy -0.4953 -0.2032) (xy 0.4953 -0.2032) (xy 0.4953 1.6002) (xy -0.4953 1.6002)
			)
			(stroke
				(width 0)
				(type default)
			)
			(fill no)
			(layer "F.CrtYd")
		)
		(fp_line
			(start -0.4953 1.6002)
			(end -0.4953 -0.2032)
			(stroke
				(width 0.1)
				(type default)
			)
			(layer "F.Fab")
		)
		(fp_line
			(start 0.4953 1.6002)
			(end -0.4953 1.6002)
			(stroke
				(width 0.1)
				(type default)
			)
			(layer "F.Fab")
		)
		(fp_line
			(start -0.4953 -0.2032)
			(end 0.4953 -0.2032)
			(stroke
				(width 0.1)
				(type default)
			)
			(layer "F.Fab")
		)
		(fp_line
			(start 0.4953 -0.2032)
			(end 0.4953 1.6002)
			(stroke
				(width 0.1)
				(type default)
			)
			(layer "F.Fab")
		)
		(pad "1" smd rect
			(at 0 0 270)
			(size 0.762 0.889)
			(layers "F.Cu" "F.Mask" "F.Paste")
			(net "PVPP_DEF")
		)
		(pad "2" smd rect
			(at 0 1.397 270)
			(size 0.762 0.889)
			(layers "F.Cu" "F.Mask" "F.Paste")
			(net "GND")
		)
		(zone
			(layer "F.Cu")
			(hatch none 0.5)
			(connect_pads
				(clearance 0)
			)
			(min_thickness 0.25)
			(keepout
				(tracks not_allowed)
				(vias allowed)
				(pads allowed)
				(copperpour not_allowed)
				(footprints allowed)
			)
			(placement
				(enabled no)
				(sheetname "")
			)
			(fill
				(thermal_gap 0.5)
				(thermal_bridge_width 0.5)
				(island_removal_mode 0)
			)
			(polygon
				(pts
					(xy 318.1985 -130.7338) (xy 318.1985 -129.9718) (xy 317.6905 -129.9718) (xy 317.6905 -130.7338)
				)
			)
		)
	)
	(footprint ""
		(layer "F.Cu")
		(at 401.319492 -10.917936)
		(property "Reference" "C8G2"
			(at 0 0 0)
			(layer "F.SilkS")
			(hide yes)
			(effects
				(font
					(size 1.27 1.27)
				)
			)
		)
		(property "Value" ""
			(at 0 0 0)
			(layer "F.Fab")
			(effects
				(font
					(size 1.27 1.27)
				)
			)
		)
		(duplicate_pad_numbers_are_jumpers no)
		(fp_rect
			(start -0.3048 0.9906)
			(end 0.3048 -0.1016)
			(stroke
				(width 0)
				(type default)
			)
			(fill no)
			(layer "F.CrtYd")
		)
		(fp_line
			(start -0.3048 -0.1016)
			(end -0.3048 0.9906)
			(stroke
				(width 0.1)
				(type default)
			)
			(layer "F.Fab")
		)
		(fp_line
			(start -0.3048 0.9906)
			(end 0.3048 0.9906)
			(stroke
				(width 0.1)
				(type default)
			)
			(layer "F.Fab")
		)
		(fp_line
			(start 0.3048 -0.1016)
			(end -0.3048 -0.1016)
			(stroke
				(width 0.1)
				(type default)
			)
			(layer "F.Fab")
		)
		(fp_line
			(start 0.3048 0.9906)
			(end 0.3048 -0.1016)
			(stroke
				(width 0.1)
				(type default)
			)
			(layer "F.Fab")
		)
		(pad "1" smd rect
			(at 0 0)
			(size 0.508 0.508)
			(layers "F.Cu" "F.Mask" "F.Paste")
			(net "P3E_CPU0_PE2_SS_TXN<4>")
		)
		(pad "2" smd rect
			(at 0 0.889)
			(size 0.508 0.508)
			(layers "F.Cu" "F.Mask" "F.Paste")
			(net "P3E_CPU0_PE2_SS_C_TXN<4>")
		)
		(zone
			(layer "F.Cu")
			(hatch none 0.5)
			(connect_pads
				(clearance 0)
			)
			(min_thickness 0.25)
			(keepout
				(tracks not_allowed)
				(vias allowed)
				(pads allowed)
				(copperpour not_allowed)
				(footprints allowed)
			)
			(placement
				(enabled no)
				(sheetname "")
			)
			(fill
				(thermal_gap 0.5)
				(thermal_bridge_width 0.5)
				(island_removal_mode 0)
			)
			(polygon
				(pts
					(xy 401.065492 -10.282936) (xy 401.573492 -10.282936) (xy 401.573492 -10.663936) (xy 401.065492 -10.663936)
				)
			)
		)
		(zone
			(layer "F.Cu")
			(hatch none 0.5)
			(connect_pads
				(clearance 0)
			)
			(min_thickness 0.25)
			(keepout
				(tracks allowed)
				(vias not_allowed)
				(pads allowed)
				(copperpour not_allowed)
				(footprints allowed)
			)
			(placement
				(enabled no)
				(sheetname "")
			)
			(fill
				(thermal_gap 0.5)
				(thermal_bridge_width 0.5)
				(island_removal_mode 0)
			)
			(polygon
				(pts
					(xy 401.065492 -10.282936) (xy 401.573492 -10.282936) (xy 401.573492 -10.663936) (xy 401.065492 -10.663936)
				)
			)
		)
	)
)
